(kicad_pcb
	(version 20260206)
	(generator "pcbnew")
	(generator_version "10.0")
	(general
		(thickness 1.21888)
		(legacy_teardrops no)
	)
	(paper "A4")
	(title_block
		(title "timecard-v9 — TimeCard-DC-V9_EXP.PcbDoc")
		(comment 1 "Time Appliance Project (Time Card) / footprints 323-333 of 402")
	)
	(layers
		(0 "F.Cu" signal "TOP")
		(4 "In1.Cu" signal "SGND")
		(6 "In2.Cu" signal "IN1")
		(8 "In3.Cu" signal "IN2")
		(10 "In4.Cu" signal "SGND1")
		(2 "B.Cu" signal "BOTTOM")
		(9 "F.Adhes" user "F.Adhesive")
		(11 "B.Adhes" user "B.Adhesive")
		(13 "F.Paste" user "Top Paste")
		(15 "B.Paste" user "Bottom Paste")
		(5 "F.SilkS" user "Top Overlay")
		(7 "B.SilkS" user "Bottom Overlay")
		(1 "F.Mask" user "Top Solder")
		(3 "B.Mask" user "Bottom Solder")
		(17 "Dwgs.User" user "User.Drawings")
		(19 "Cmts.User" user "User.Comments")
		(21 "Eco1.User" user "User.Eco1")
		(23 "Eco2.User" user "User.Eco2")
		(25 "Edge.Cuts" user)
		(27 "Margin" user)
		(31 "F.CrtYd" user "Top Courtyard")
		(29 "B.CrtYd" user "Bottom Courtyard")
		(35 "F.Fab" user "Top Component Center")
		(33 "B.Fab" user "Bottom Component Center")
	)
	(footprint "Vault:FP-0402-L_1_0_1-W_0_5_0_1-IPC_C"
		(layer "B.Cu")
		(at 126.5216 55.9162 90)
		(property "Reference" "C98"
			(at 2.30817 0.615561 90)
			(unlocked yes)
			(layer "B.SilkS")
			(effects
				(font
					(size 0.762 0.762)
					(thickness 0.2032)
				)
				(justify mirror)
			)
		)
		(property "Value" "0.1uF_25V_0402"
			(at -2.465551 -9.813815 0)
			(unlocked yes)
			(layer "B.SilkS")
			(hide yes)
			(effects
				(font
					(size 0.762 0.762)
					(thickness 0.2032)
				)
				(justify mirror)
			)
		)
		(sheetname "10-M2_GPS")
		(sheetfile "10-M2_GPS.kicad_sch")
		(duplicate_pad_numbers_are_jumpers no)
		(fp_line
			(start -0.65607 -0.7)
			(end 0.65607 -0.7)
			(stroke
				(width 0.2)
				(type solid)
			)
			(layer "B.SilkS")
		)
		(fp_line
			(start -0.65607 0.7)
			(end 0.65607 0.7)
			(stroke
				(width 0.2)
				(type solid)
			)
			(layer "B.SilkS")
		)
		(fp_line
			(start 0.75607 -0.4)
			(end 0.75607 0.4)
			(stroke
				(width 0.2)
				(type solid)
			)
			(layer "B.CrtYd")
		)
		(fp_line
			(start -0.75607 -0.4)
			(end 0.75607 -0.4)
			(stroke
				(width 0.2)
				(type solid)
			)
			(layer "B.CrtYd")
		)
		(fp_line
			(start -0.75607 -0.4)
			(end -0.75607 0.4)
			(stroke
				(width 0.2)
				(type solid)
			)
			(layer "B.CrtYd")
		)
		(fp_line
			(start -0.75607 0.4)
			(end 0.75607 0.4)
			(stroke
				(width 0.2)
				(type solid)
			)
			(layer "B.CrtYd")
		)
		(fp_line
			(start 0 -0.5)
			(end 0 0.5)
			(stroke
				(width 0.1)
				(type solid)
			)
			(layer "B.Fab")
		)
		(fp_line
			(start 0.75607 -0.4)
			(end 0.75607 0.4)
			(stroke
				(width 0.2)
				(type solid)
			)
			(layer "B.Fab")
		)
		(fp_line
			(start -0.75607 -0.4)
			(end 0.75607 -0.4)
			(stroke
				(width 0.2)
				(type solid)
			)
			(layer "B.Fab")
		)
		(fp_line
			(start -0.75607 -0.4)
			(end -0.75607 0.4)
			(stroke
				(width 0.2)
				(type solid)
			)
			(layer "B.Fab")
		)
		(fp_line
			(start -0.5 0)
			(end 0.5 0)
			(stroke
				(width 0.1)
				(type solid)
			)
			(layer "B.Fab")
		)
		(fp_line
			(start -0.75607 0.4)
			(end 0.75607 0.4)
			(stroke
				(width 0.2)
				(type solid)
			)
			(layer "B.Fab")
		)
		(fp_text user "${REFERENCE}"
			(at -0.00002 -0.09602 270)
			(unlocked yes)
			(layer "B.Fab")
			(effects
				(font
					(face "Arial")
					(size 0.63 0.63)
					(thickness 0.1)
				)
				(justify left bottom mirror)
			)
		)
		(pad "1" smd rect
			(at -0.36554 0 90)
			(size 0.58106 0.51213)
			(layers "B.Cu" "B.Mask" "B.Paste")
			(net "+3.3V")
			(solder_mask_margin 0)
			(solder_paste_margin 0)
		)
		(pad "2" smd rect
			(at 0.36554 0 90)
			(size 0.58106 0.51213)
			(layers "B.Cu" "B.Mask" "B.Paste")
			(net "GND")
			(solder_mask_margin 0)
			(solder_paste_margin 0)
		)
	)
	(footprint "Vault:RESC1005X40X25LL05T05"
		(layer "B.Cu")
		(at 95.2756 58.4511 180)
		(property "Reference" "R4"
			(at -0.646 0.641555 0)
			(unlocked yes)
			(layer "B.SilkS")
			(effects
				(font
					(size 0.762 0.762)
					(thickness 0.2286)
				)
				(justify left bottom mirror)
			)
		)
		(property "Value" "0_1%_0402"
			(at -0.2227 8.970755 0)
			(unlocked yes)
			(layer "B.SilkS")
			(hide yes)
			(effects
				(font
					(size 0.762 0.762)
					(thickness 0.2286)
				)
				(justify left bottom mirror)
			)
		)
		(sheetname "03-POWER")
		(sheetfile "03-POWER.kicad_sch")
		(duplicate_pad_numbers_are_jumpers no)
		(pad "1" smd rect
			(at -0.4 0 90)
			(size 0.45 0.45)
			(layers "B.Cu" "B.Mask" "B.Paste")
			(net "+12V")
		)
		(pad "2" smd rect
			(at 0.4 0 90)
			(size 0.45 0.45)
			(layers "B.Cu" "B.Mask" "B.Paste")
			(net "NetR4_2")
		)
	)
	(footprint "Vault:RESC1005X40X25ML05T05"
		(layer "B.Cu")
		(at 207.81727 126.86632 180)
		(property "Reference" "R49"
			(at -0.18323 -1.047849 180)
			(unlocked yes)
			(layer "B.SilkS")
			(effects
				(font
					(size 0.762 0.762)
					(thickness 0.254)
				)
				(justify mirror)
			)
		)
		(property "Value" "10K_5%_0402"
			(at -2.884671 -8.061875 90)
			(unlocked yes)
			(layer "B.SilkS")
			(hide yes)
			(effects
				(font
					(size 0.762 0.762)
					(thickness 0.254)
				)
				(justify mirror)
			)
		)
		(sheetname "09-USBUart_PPSMUX_UARTMUX")
		(sheetfile "09-USBUart_PPSMUX_UARTMUX.kicad_sch")
		(duplicate_pad_numbers_are_jumpers no)
		(pad "1" smd rect
			(at -0.5 0 90)
			(size 0.65 0.65)
			(layers "B.Cu" "B.Mask" "B.Paste")
			(net "NetR49_1")
		)
		(pad "2" smd rect
			(at 0.5 0 90)
			(size 0.65 0.65)
			(layers "B.Cu" "B.Mask" "B.Paste")
			(net "+3.3V")
		)
	)
	(footprint "Vault:RESC1005X40X25NL10T10"
		(layer "B.Cu")
		(at 184.3216 92.2162 -90)
		(property "Reference" "R183"
			(at 2.396998 -2.70424 180)
			(unlocked yes)
			(layer "B.SilkS")
			(effects
				(font
					(size 1.524 1.524)
					(thickness 0.254)
				)
				(justify mirror)
			)
		)
		(property "Value" "20K_1%_0402"
			(at -2.759202 -8.163475 180)
			(unlocked yes)
			(layer "B.SilkS")
			(hide yes)
			(effects
				(font
					(size 1.524 1.524)
					(thickness 0.254)
				)
				(justify mirror)
			)
		)
		(sheetname "03-POWER")
		(sheetfile "03-POWER.kicad_sch")
		(duplicate_pad_numbers_are_jumpers no)
		(pad "1" smd rect
			(at -0.425 0 180)
			(size 0.6 0.65)
			(layers "B.Cu" "B.Mask" "B.Paste")
			(net "+12V")
		)
		(pad "2" smd rect
			(at 0.425 0 180)
			(size 0.6 0.65)
			(layers "B.Cu" "B.Mask" "B.Paste")
			(net "NetR183_2")
		)
	)
	(footprint "Vault:RESC1608X55X30NL15T15"
		(layer "B.Cu")
		(at 79.4216 54.4662 180)
		(property "Reference" "R38"
			(at -2.9714 -0.176931 0)
			(unlocked yes)
			(layer "B.SilkS")
			(effects
				(font
					(size 0.762 0.762)
					(thickness 0.2286)
				)
				(justify mirror)
			)
		)
		(property "Value" "200 OHM"
			(at -2.935471 -4.78626 90)
			(unlocked yes)
			(layer "B.SilkS")
			(hide yes)
			(effects
				(font
					(size 0.762 0.762)
					(thickness 0.2286)
				)
				(justify mirror)
			)
		)
		(sheetname "02-USER_IO_STATUS")
		(sheetfile "02-USER_IO_STATUS.kicad_sch")
		(duplicate_pad_numbers_are_jumpers no)
		(pad "1" smd rect
			(at -0.675 0 90)
			(size 0.95 0.8)
			(layers "B.Cu" "B.Mask" "B.Paste")
			(net "LED3")
		)
		(pad "2" smd rect
			(at 0.675 0 90)
			(size 0.95 0.8)
			(layers "B.Cu" "B.Mask" "B.Paste")
			(net "NetD10_1")
		)
	)
	(footprint "Vault:RESC1608X55X25LL10T15"
		(layer "B.Cu")
		(at 132.0216 88.6162 180)
		(property "Reference" "R11"
			(at 0.228605 1.273079 0)
			(unlocked yes)
			(layer "B.SilkS")
			(effects
				(font
					(size 0.762 0.762)
					(thickness 0.2286)
				)
				(justify mirror)
			)
		)
		(property "Value" "4.7K"
			(at -2.630671 -2.57723 90)
			(unlocked yes)
			(layer "B.SilkS")
			(hide yes)
			(effects
				(font
					(size 0.762 0.762)
					(thickness 0.2286)
				)
				(justify mirror)
			)
		)
		(sheetname "06-MAC")
		(sheetfile "06-MAC.kicad_sch")
		(duplicate_pad_numbers_are_jumpers no)
		(pad "1" smd rect
			(at -0.65 0 90)
			(size 0.8 0.6)
			(layers "B.Cu" "B.Mask" "B.Paste")
			(net "GND")
		)
		(pad "2" smd rect
			(at 0.65 0 90)
			(size 0.8 0.6)
			(layers "B.Cu" "B.Mask" "B.Paste")
			(net "FPGA_MAC_PPS_DIFF_IN0")
		)
	)
	(footprint "Vault:FP-0402-L_1_0_1-W_0_5_0_1-IPC_C"
		(layer "B.Cu")
		(at 223.56155 125.79915 90)
		(property "Reference" "C115"
			(at 2.32895 0.886971 90)
			(unlocked yes)
			(layer "B.SilkS")
			(effects
				(font
					(size 0.762 0.762)
					(thickness 0.254)
				)
				(justify mirror)
			)
		)
		(property "Value" "0.1uF_25V_0402"
			(at -2.465561 -9.864615 0)
			(unlocked yes)
			(layer "B.SilkS")
			(hide yes)
			(effects
				(font
					(size 0.762 0.762)
					(thickness 0.254)
				)
				(justify mirror)
			)
		)
		(sheetname "09-USBUart_PPSMUX_UARTMUX")
		(sheetfile "09-USBUart_PPSMUX_UARTMUX.kicad_sch")
		(duplicate_pad_numbers_are_jumpers no)
		(fp_line
			(start -0.65607 -0.7)
			(end 0.65606 -0.7)
			(stroke
				(width 0.2)
				(type solid)
			)
			(layer "B.SilkS")
		)
		(fp_line
			(start -0.65607 0.7)
			(end 0.65606 0.7)
			(stroke
				(width 0.2)
				(type solid)
			)
			(layer "B.SilkS")
		)
		(fp_line
			(start 0.75606 -0.4)
			(end 0.75606 0.4)
			(stroke
				(width 0.2)
				(type solid)
			)
			(layer "B.CrtYd")
		)
		(fp_line
			(start -0.75607 -0.4)
			(end 0.75606 -0.4)
			(stroke
				(width 0.2)
				(type solid)
			)
			(layer "B.CrtYd")
		)
		(fp_line
			(start -0.75607 -0.4)
			(end -0.75607 0.4)
			(stroke
				(width 0.2)
				(type solid)
			)
			(layer "B.CrtYd")
		)
		(fp_line
			(start -0.75607 0.4)
			(end 0.75606 0.4)
			(stroke
				(width 0.2)
				(type solid)
			)
			(layer "B.CrtYd")
		)
		(fp_line
			(start 0 -0.5)
			(end 0 0.5)
			(stroke
				(width 0.1)
				(type solid)
			)
			(layer "B.Fab")
		)
		(fp_line
			(start 0.75606 -0.4)
			(end 0.75606 0.4)
			(stroke
				(width 0.2)
				(type solid)
			)
			(layer "B.Fab")
		)
		(fp_line
			(start -0.75607 -0.4)
			(end 0.75606 -0.4)
			(stroke
				(width 0.2)
				(type solid)
			)
			(layer "B.Fab")
		)
		(fp_line
			(start -0.75607 -0.4)
			(end -0.75607 0.4)
			(stroke
				(width 0.2)
				(type solid)
			)
			(layer "B.Fab")
		)
		(fp_line
			(start -0.5 0)
			(end 0.49999 0)
			(stroke
				(width 0.1)
				(type solid)
			)
			(layer "B.Fab")
		)
		(fp_line
			(start -0.75607 0.4)
			(end 0.75606 0.4)
			(stroke
				(width 0.2)
				(type solid)
			)
			(layer "B.Fab")
		)
		(fp_text user "${REFERENCE}"
			(at -0.00002 -0.09602 270)
			(unlocked yes)
			(layer "B.Fab")
			(effects
				(font
					(face "Arial")
					(size 0.63 0.63)
					(thickness 0.1)
				)
				(justify left bottom mirror)
			)
		)
		(pad "1" smd rect
			(at -0.36554 0 90)
			(size 0.58106 0.51213)
			(layers "B.Cu" "B.Mask" "B.Paste")
			(net "FTDI_VBUS")
			(solder_mask_margin 0)
			(solder_paste_margin 0)
		)
		(pad "2" smd rect
			(at 0.36553 0 90)
			(size 0.58106 0.51213)
			(layers "B.Cu" "B.Mask" "B.Paste")
			(net "GND")
			(solder_mask_margin 0)
			(solder_paste_margin 0)
		)
	)
	(footprint "Vault:RESC1005X40X25LL05T05"
		(layer "B.Cu")
		(at 113.78072 88.0662 -90)
		(property "Reference" "R52"
			(at 0.0214 -0.913949 270)
			(unlocked yes)
			(layer "B.SilkS")
			(effects
				(font
					(size 0.762 0.762)
					(thickness 0.2286)
				)
				(justify mirror)
			)
		)
		(property "Value" "4.7K_0402"
			(at -3.024391 -2.374045 180)
			(unlocked yes)
			(layer "B.SilkS")
			(hide yes)
			(effects
				(font
					(size 0.762 0.762)
					(thickness 0.2286)
				)
				(justify mirror)
			)
		)
		(sheetname "05-GPS_IMU_SENSORS")
		(sheetfile "05-GPS_IMU_SENSORS.kicad_sch")
		(duplicate_pad_numbers_are_jumpers no)
		(pad "1" smd rect
			(at -0.4 0 180)
			(size 0.45 0.45)
			(layers "B.Cu" "B.Mask" "B.Paste")
			(net "NetR52_1")
		)
		(pad "2" smd rect
			(at 0.4 0 180)
			(size 0.45 0.45)
			(layers "B.Cu" "B.Mask" "B.Paste")
			(net "BNO_P3V3")
		)
	)
	(footprint "Vault:FP-0402-L_1_0_1-W_0_5_0_1-IPC_C"
		(layer "B.Cu")
		(at 227.8216 115.7162)
		(property "Reference" "C93"
			(at 0.2286 1.473069 180)
			(unlocked yes)
			(layer "B.SilkS")
			(effects
				(font
					(size 0.762 0.762)
					(thickness 0.2286)
				)
				(justify mirror)
			)
		)
		(property "Value" "0.1uF_25V_0402"
			(at -2.465551 -9.839215 270)
			(unlocked yes)
			(layer "B.SilkS")
			(hide yes)
			(effects
				(font
					(size 0.762 0.762)
					(thickness 0.2286)
				)
				(justify mirror)
			)
		)
		(sheetname "09-USBUart_PPSMUX_UARTMUX")
		(sheetfile "09-USBUart_PPSMUX_UARTMUX.kicad_sch")
		(duplicate_pad_numbers_are_jumpers no)
		(fp_line
			(start -0.65607 -0.7)
			(end 0.65607 -0.7)
			(stroke
				(width 0.2)
				(type solid)
			)
			(layer "B.SilkS")
		)
		(fp_line
			(start -0.65607 0.7)
			(end 0.65607 0.7)
			(stroke
				(width 0.2)
				(type solid)
			)
			(layer "B.SilkS")
		)
		(fp_line
			(start -0.75607 -0.4)
			(end 0.75607 -0.4)
			(stroke
				(width 0.2)
				(type solid)
			)
			(layer "B.CrtYd")
		)
		(fp_line
			(start -0.75607 0.4)
			(end -0.75607 -0.4)
			(stroke
				(width 0.2)
				(type solid)
			)
			(layer "B.CrtYd")
		)
		(fp_line
			(start -0.75607 0.4)
			(end 0.75607 0.4)
			(stroke
				(width 0.2)
				(type solid)
			)
			(layer "B.CrtYd")
		)
		(fp_line
			(start 0.75607 0.4)
			(end 0.75607 -0.4)
			(stroke
				(width 0.2)
				(type solid)
			)
			(layer "B.CrtYd")
		)
		(fp_line
			(start -0.75607 -0.4)
			(end 0.75607 -0.4)
			(stroke
				(width 0.2)
				(type solid)
			)
			(layer "B.Fab")
		)
		(fp_line
			(start -0.75607 0.4)
			(end -0.75607 -0.4)
			(stroke
				(width 0.2)
				(type solid)
			)
			(layer "B.Fab")
		)
		(fp_line
			(start -0.75607 0.4)
			(end 0.75607 0.4)
			(stroke
				(width 0.2)
				(type solid)
			)
			(layer "B.Fab")
		)
		(fp_line
			(start -0.5 0)
			(end 0.5 0)
			(stroke
				(width 0.1)
				(type solid)
			)
			(layer "B.Fab")
		)
		(fp_line
			(start 0 0.5)
			(end 0 -0.5)
			(stroke
				(width 0.1)
				(type solid)
			)
			(layer "B.Fab")
		)
		(fp_line
			(start 0.75607 0.4)
			(end 0.75607 -0.4)
			(stroke
				(width 0.2)
				(type solid)
			)
			(layer "B.Fab")
		)
		(fp_text user "${REFERENCE}"
			(at -0.00002 -0.09601 180)
			(unlocked yes)
			(layer "B.Fab")
			(effects
				(font
					(face "Arial")
					(size 0.63 0.63)
					(thickness 0.1)
				)
				(justify left bottom mirror)
			)
		)
		(pad "1" smd rect
			(at -0.36554 0)
			(size 0.58106 0.51213)
			(layers "B.Cu" "B.Mask" "B.Paste")
			(net "NetC92_1")
			(solder_mask_margin 0)
			(solder_paste_margin 0)
		)
		(pad "2" smd rect
			(at 0.36554 0)
			(size 0.58106 0.51213)
			(layers "B.Cu" "B.Mask" "B.Paste")
			(net "GND")
			(solder_mask_margin 0)
			(solder_paste_margin 0)
		)
	)
	(footprint "Vault:FP-0402-L_1_0_1-W_0_5_0_1-IPC_C"
		(layer "B.Cu")
		(at 201.0716 121.19078)
		(property "Reference" "C102"
			(at 2.1468 0.152341 0)
			(unlocked yes)
			(layer "B.SilkS")
			(effects
				(font
					(size 0.762 0.762)
					(thickness 0.2032)
				)
				(justify mirror)
			)
		)
		(property "Value" "0.1uF_25V_0402"
			(at -2.465551 -9.813805 270)
			(unlocked yes)
			(layer "B.SilkS")
			(hide yes)
			(effects
				(font
					(size 0.762 0.762)
					(thickness 0.2032)
				)
				(justify mirror)
			)
		)
		(sheetname "10-M2_GPS")
		(sheetfile "10-M2_GPS.kicad_sch")
		(duplicate_pad_numbers_are_jumpers no)
		(fp_line
			(start -0.65607 -0.7)
			(end 0.65606 -0.7)
			(stroke
				(width 0.2)
				(type solid)
			)
			(layer "B.SilkS")
		)
		(fp_line
			(start -0.65607 0.70001)
			(end 0.65606 0.70001)
			(stroke
				(width 0.2)
				(type solid)
			)
			(layer "B.SilkS")
		)
		(fp_line
			(start -0.75607 -0.4)
			(end 0.75606 -0.4)
			(stroke
				(width 0.2)
				(type solid)
			)
			(layer "B.CrtYd")
		)
		(fp_line
			(start -0.75607 0.4)
			(end -0.75607 -0.4)
			(stroke
				(width 0.2)
				(type solid)
			)
			(layer "B.CrtYd")
		)
		(fp_line
			(start -0.75607 0.4)
			(end 0.75606 0.4)
			(stroke
				(width 0.2)
				(type solid)
			)
			(layer "B.CrtYd")
		)
		(fp_line
			(start 0.75606 0.4)
			(end 0.75606 -0.4)
			(stroke
				(width 0.2)
				(type solid)
			)
			(layer "B.CrtYd")
		)
		(fp_line
			(start -0.75607 -0.4)
			(end 0.75606 -0.4)
			(stroke
				(width 0.2)
				(type solid)
			)
			(layer "B.Fab")
		)
		(fp_line
			(start -0.75607 0.4)
			(end -0.75607 -0.4)
			(stroke
				(width 0.2)
				(type solid)
			)
			(layer "B.Fab")
		)
		(fp_line
			(start -0.75607 0.4)
			(end 0.75606 0.4)
			(stroke
				(width 0.2)
				(type solid)
			)
			(layer "B.Fab")
		)
		(fp_line
			(start -0.5 0)
			(end 0.5 0)
			(stroke
				(width 0.1)
				(type solid)
			)
			(layer "B.Fab")
		)
		(fp_line
			(start 0 0.5)
			(end 0 -0.49999)
			(stroke
				(width 0.1)
				(type solid)
			)
			(layer "B.Fab")
		)
		(fp_line
			(start 0.75606 0.4)
			(end 0.75606 -0.4)
			(stroke
				(width 0.2)
				(type solid)
			)
			(layer "B.Fab")
		)
		(fp_text user "${REFERENCE}"
			(at -0.00001 -0.09601 180)
			(unlocked yes)
			(layer "B.Fab")
			(effects
				(font
					(face "Arial")
					(size 0.63 0.63)
					(thickness 0.1)
				)
				(justify left bottom mirror)
			)
		)
		(pad "1" smd rect
			(at -0.36554 0)
			(size 0.58106 0.51213)
			(layers "B.Cu" "B.Mask" "B.Paste")
			(net "GNSS2_P3V3")
			(solder_mask_margin 0)
			(solder_paste_margin 0)
		)
		(pad "2" smd rect
			(at 0.36553 0)
			(size 0.58106 0.51213)
			(layers "B.Cu" "B.Mask" "B.Paste")
			(net "GND")
			(solder_mask_margin 0)
			(solder_paste_margin 0)
		)
	)
	(footprint "Capacitors:CAPC1005X06N"
		(layer "B.Cu")
		(at 140.5596 151.7886 90)
		(property "Reference" "C52"
			(at 2.41349 -0.613855 270)
			(unlocked yes)
			(layer "B.SilkS")
			(effects
				(font
					(size 0.762 0.762)
					(thickness 0.2286)
				)
				(justify left bottom mirror)
			)
		)
		(property "Value" "CAP_0402_0.1UF_50V"
			(at -3.382645 0.2921 0)
			(unlocked yes)
			(layer "B.SilkS")
			(hide yes)
			(effects
				(font
					(size 0.762 0.762)
					(thickness 0.2286)
				)
				(justify left bottom mirror)
			)
		)
		(sheetname "04-PCIe_JTAG")
		(sheetfile "04-PCIe_JTAG.kicad_sch")
		(duplicate_pad_numbers_are_jumpers no)
		(pad "1" smd rect
			(at -0.43 0)
			(size 0.64 0.68)
			(layers "B.Cu" "B.Mask" "B.Paste")
			(net "NetC52_1")
		)
		(pad "2" smd rect
			(at 0.43 0)
			(size 0.64 0.68)
			(layers "B.Cu" "B.Mask" "B.Paste")
			(net "PCIE_TX3_P")
		)
	)
)
